# SCM (Grand Teton) — schematic netlist excerpt (pin names and nets, part order shuffled) for the footprints in the layout excerpt that follows; sources: Cadence DE-HDL packaged netlist, KiCad conversion of 12092022_DA0F0TMDCD0_F0T_Management_Board_D_brd_V3_OCP.brd

R871  Q_RES  0 5% EMPTY  pkg 0402LF  page 52 : A = EN_P3V3_R1 ; B = PWRGD_EN_P3V3_R
R752  Q_RES  33.2 1% CHIP  pkg 0402LF  page 25 : A = RST_SPI_FLASH_N ; B = RST_SPI_FLASH_R_N

(kicad_pcb
	(version 20260206)
	(generator "pcbnew")
	(generator_version "10.0")
	(general
		(thickness 1.6)
		(legacy_teardrops no)
	)
	(paper "A4")
	(title_block
		(title "12092022_DA0F0TMDCD0_F0T_Management_Board_D_brd_V3_OCP.brd")
		(comment 1 "Grand Teton / footprints 430-431 of 1440")
	)
	(layers
		(0 "F.Cu" signal "TOP")
		(4 "In1.Cu" signal "GND")
		(6 "In2.Cu" signal "IN1")
		(8 "In3.Cu" signal "GND1")
		(10 "In4.Cu" signal "IN2")
		(12 "In5.Cu" signal "VCC")
		(14 "In6.Cu" signal "VCC1")
		(16 "In7.Cu" signal "IN3")
		(18 "In8.Cu" signal "GND2")
		(20 "In9.Cu" signal "IN4")
		(22 "In10.Cu" signal "GND3")
		(2 "B.Cu" signal "BOTTOM")
		(9 "F.Adhes" user "F.Adhesive")
		(11 "B.Adhes" user "B.Adhesive")
		(13 "F.Paste" user "Package Geometry/Pastemask Top")
		(15 "B.Paste" user "Package Geometry/Pastemask Bottom")
		(5 "F.SilkS" user "Ref Des/Silkscreen Top")
		(7 "B.SilkS" user "Ref Des/Silkscreen Bottom")
		(1 "F.Mask" user "Board Geometry/Soldermask Top")
		(3 "B.Mask" user "Board Geometry/Soldermask Bottom")
		(17 "Dwgs.User" user "User.Drawings")
		(19 "Cmts.User" user "User.Comments")
		(21 "Eco1.User" user "User.Eco1")
		(23 "Eco2.User" user "User.Eco2")
		(25 "Edge.Cuts" user "Board Geometry/Outline")
		(27 "Margin" user)
		(31 "F.CrtYd" user "Package Geometry/Place Bound Top")
		(29 "B.CrtYd" user "Package Geometry/Place Bound Bottom")
		(35 "F.Fab" user "Ref Des/Assembly Top")
		(33 "B.Fab" user "Ref Des/Assembly Bottom")
	)
	(footprint ""
		(layer "F.Cu")
		(at 20.701 -42.9006 -90)
		(property "Reference" "R752"
			(at 0 0 270)
			(layer "F.SilkS")
			(hide yes)
			(effects
				(font
					(size 1.27 1.27)
				)
			)
		)
		(property "Value" ""
			(at 0 0 270)
			(layer "F.Fab")
			(effects
				(font
					(size 1.27 1.27)
				)
			)
		)
		(duplicate_pad_numbers_are_jumpers no)
		(fp_line
			(start -0.7874 0.4064)
			(end -0.7874 -0.4064)
			(stroke
				(width 0.1524)
				(type default)
			)
			(layer "F.SilkS")
		)
		(fp_line
			(start 0.7874 0.4064)
			(end -0.7874 0.4064)
			(stroke
				(width 0.1524)
				(type default)
			)
			(layer "F.SilkS")
		)
		(fp_line
			(start -0.7874 -0.4064)
			(end 0.7874 -0.4064)
			(stroke
				(width 0.1524)
				(type default)
			)
			(layer "F.SilkS")
		)
		(fp_line
			(start 0.7874 -0.4064)
			(end 0.7874 0.4064)
			(stroke
				(width 0.1524)
				(type default)
			)
			(layer "F.SilkS")
		)
		(fp_line
			(start -0.67945 0.3048)
			(end -0.67945 -0.305054)
			(stroke
				(width 0.1)
				(type default)
			)
			(layer "F.Fab")
		)
		(fp_line
			(start -0.12065 0.3048)
			(end -0.67945 0.3048)
			(stroke
				(width 0.1)
				(type default)
			)
			(layer "F.Fab")
		)
		(fp_line
			(start 0.120396 0.3048)
			(end 0.120396 0.2794)
			(stroke
				(width 0.1)
				(type default)
			)
			(layer "F.Fab")
		)
		(fp_line
			(start 0.67945 0.3048)
			(end 0.120396 0.3048)
			(stroke
				(width 0.1)
				(type default)
			)
			(layer "F.Fab")
		)
		(fp_line
			(start -0.12065 0.2794)
			(end -0.12065 0.3048)
			(stroke
				(width 0.1)
				(type default)
			)
			(layer "F.Fab")
		)
		(fp_line
			(start 0.120396 0.2794)
			(end -0.12065 0.2794)
			(stroke
				(width 0.1)
				(type default)
			)
			(layer "F.Fab")
		)
		(fp_line
			(start -0.12065 -0.2794)
			(end 0.12065 -0.2794)
			(stroke
				(width 0.1)
				(type default)
			)
			(layer "F.Fab")
		)
		(fp_line
			(start 0.12065 -0.2794)
			(end 0.12065 -0.3048)
			(stroke
				(width 0.1)
				(type default)
			)
			(layer "F.Fab")
		)
		(fp_line
			(start 0.12065 -0.3048)
			(end 0.67945 -0.3048)
			(stroke
				(width 0.1)
				(type default)
			)
			(layer "F.Fab")
		)
		(fp_line
			(start 0.67945 -0.3048)
			(end 0.67945 0.3048)
			(stroke
				(width 0.1)
				(type default)
			)
			(layer "F.Fab")
		)
		(fp_line
			(start -0.67945 -0.305054)
			(end -0.12065 -0.305054)
			(stroke
				(width 0.1)
				(type default)
			)
			(layer "F.Fab")
		)
		(fp_line
			(start -0.12065 -0.305054)
			(end -0.12065 -0.2794)
			(stroke
				(width 0.1)
				(type default)
			)
			(layer "F.Fab")
		)
		(pad "1" smd circle
			(at -0.40005 0 270)
			(size 0 0)
			(layers "F.Cu" "F.Mask" "F.Paste")
			(net "RST_SPI_FLASH_N")
		)
		(pad "2" smd circle
			(at 0.40005 0 270)
			(size 0 0)
			(layers "F.Cu" "F.Mask" "F.Paste")
			(net "RST_SPI_FLASH_R_N")
		)
	)
	(footprint ""
		(layer "F.Cu")
		(at 11.4554 -62.2046 180)
		(property "Reference" "R871"
			(at 0 0 180)
			(layer "F.SilkS")
			(hide yes)
			(effects
				(font
					(size 1.27 1.27)
				)
			)
		)
		(property "Value" ""
			(at 0 0 180)
			(layer "F.Fab")
			(effects
				(font
					(size 1.27 1.27)
				)
			)
		)
		(duplicate_pad_numbers_are_jumpers no)
		(fp_line
			(start 0.7874 0.4064)
			(end -0.7874 0.4064)
			(stroke
				(width 0.1524)
				(type default)
			)
			(layer "F.SilkS")
		)
		(fp_line
			(start 0.7874 -0.4064)
			(end 0.7874 0.4064)
			(stroke
				(width 0.1524)
				(type default)
			)
			(layer "F.SilkS")
		)
		(fp_line
			(start -0.7874 0.4064)
			(end -0.7874 -0.4064)
			(stroke
				(width 0.1524)
				(type default)
			)
			(layer "F.SilkS")
		)
		(fp_line
			(start -0.7874 -0.4064)
			(end 0.7874 -0.4064)
			(stroke
				(width 0.1524)
				(type default)
			)
			(layer "F.SilkS")
		)
		(fp_line
			(start 0.67945 0.3048)
			(end 0.120396 0.3048)
			(stroke
				(width 0.1)
				(type default)
			)
			(layer "F.Fab")
		)
		(fp_line
			(start 0.67945 -0.3048)
			(end 0.67945 0.3048)
			(stroke
				(width 0.1)
				(type default)
			)
			(layer "F.Fab")
		)
		(fp_line
			(start 0.12065 -0.2794)
			(end 0.12065 -0.3048)
			(stroke
				(width 0.1)
				(type default)
			)
			(layer "F.Fab")
		)
		(fp_line
			(start 0.12065 -0.3048)
			(end 0.67945 -0.3048)
			(stroke
				(width 0.1)
				(type default)
			)
			(layer "F.Fab")
		)
		(fp_line
			(start 0.120396 0.3048)
			(end 0.120396 0.2794)
			(stroke
				(width 0.1)
				(type default)
			)
			(layer "F.Fab")
		)
		(fp_line
			(start 0.120396 0.2794)
			(end -0.12065 0.2794)
			(stroke
				(width 0.1)
				(type default)
			)
			(layer "F.Fab")
		)
		(fp_line
			(start -0.12065 0.3048)
			(end -0.67945 0.3048)
			(stroke
				(width 0.1)
				(type default)
			)
			(layer "F.Fab")
		)
		(fp_line
			(start -0.12065 0.2794)
			(end -0.12065 0.3048)
			(stroke
				(width 0.1)
				(type default)
			)
			(layer "F.Fab")
		)
		(fp_line
			(start -0.12065 -0.2794)
			(end 0.12065 -0.2794)
			(stroke
				(width 0.1)
				(type default)
			)
			(layer "F.Fab")
		)
		(fp_line
			(start -0.12065 -0.305054)
			(end -0.12065 -0.2794)
			(stroke
				(width 0.1)
				(type default)
			)
			(layer "F.Fab")
		)
		(fp_line
			(start -0.67945 0.3048)
			(end -0.67945 -0.305054)
			(stroke
				(width 0.1)
				(type default)
			)
			(layer "F.Fab")
		)
		(fp_line
			(start -0.67945 -0.305054)
			(end -0.12065 -0.305054)
			(stroke
				(width 0.1)
				(type default)
			)
			(layer "F.Fab")
		)
		(pad "1" smd circle
			(at -0.40005 0 180)
			(size 0 0)
			(layers "F.Cu" "F.Mask" "F.Paste")
			(net "EN_P3V3_R1")
		)
		(pad "2" smd circle
			(at 0.40005 0 180)
			(size 0 0)
			(layers "F.Cu" "F.Mask" "F.Paste")
			(net "PWRGD_EN_P3V3_R")
		)
	)
)
